(kicad_pcb
	(version 20260206)
	(generator "pcbnew")
	(generator_version "10.0")
	(general
		(thickness 1.6)
		(legacy_teardrops no)
	)
	(paper "A4")
	(title_block
		(title "04192023_DAF0TMB3IC0_F0TG_MB_C_brd_V02_OCP.brd")
		(comment 1 "Grand Teton / footprints 2798-2803 of 8354")
	)
	(layers
		(0 "F.Cu" signal "TOP")
		(4 "In1.Cu" signal "GND")
		(6 "In2.Cu" signal "IN1")
		(8 "In3.Cu" signal "GND1")
		(10 "In4.Cu" signal "IN2")
		(12 "In5.Cu" signal "GND2")
		(14 "In6.Cu" signal "IN3")
		(16 "In7.Cu" signal "GND3")
		(18 "In8.Cu" signal "VCC")
		(20 "In9.Cu" signal "VCC1")
		(22 "In10.Cu" signal "GND4")
		(24 "In11.Cu" signal "IN4")
		(26 "In12.Cu" signal "GND5")
		(28 "In13.Cu" signal "IN5")
		(30 "In14.Cu" signal "GND6")
		(32 "In15.Cu" signal "IN6")
		(34 "In16.Cu" signal "GND7")
		(2 "B.Cu" signal "BOTTOM")
		(9 "F.Adhes" user "F.Adhesive")
		(11 "B.Adhes" user "B.Adhesive")
		(13 "F.Paste" user "Package Geometry/Pastemask Top")
		(15 "B.Paste" user "Package Geometry/Pastemask Bottom")
		(5 "F.SilkS" user "Ref Des/Silkscreen Top")
		(7 "B.SilkS" user "Ref Des/Silkscreen Bottom")
		(1 "F.Mask" user "Board Geometry/Soldermask Top")
		(3 "B.Mask" user "Board Geometry/Soldermask Bottom")
		(17 "Dwgs.User" user "User.Drawings")
		(19 "Cmts.User" user "User.Comments")
		(21 "Eco1.User" user "User.Eco1")
		(23 "Eco2.User" user "User.Eco2")
		(25 "Edge.Cuts" user "Board Geometry/Outline")
		(27 "Margin" user)
		(31 "F.CrtYd" user "Package Geometry/Place Bound Top")
		(29 "B.CrtYd" user "Package Geometry/Place Bound Bottom")
		(35 "F.Fab" user "Ref Des/Assembly Top")
		(33 "B.Fab" user "Ref Des/Assembly Bottom")
	)
	(footprint ""
		(layer "F.Cu")
		(at 421.174418 -366.202214 90)
		(property "Reference" "PC199"
			(at 0 0 90)
			(layer "F.SilkS")
			(hide yes)
			(effects
				(font
					(size 1.27 1.27)
				)
			)
		)
		(property "Value" ""
			(at 0 0 90)
			(layer "F.Fab")
			(effects
				(font
					(size 1.27 1.27)
				)
			)
		)
		(duplicate_pad_numbers_are_jumpers no)
		(fp_line
			(start 0.7874 -0.4064)
			(end 0.7874 0.4064)
			(stroke
				(width 0.1524)
				(type default)
			)
			(layer "F.SilkS")
		)
		(fp_line
			(start -0.7874 -0.4064)
			(end 0.7874 -0.4064)
			(stroke
				(width 0.1524)
				(type default)
			)
			(layer "F.SilkS")
		)
		(fp_line
			(start 0.7874 0.4064)
			(end -0.7874 0.4064)
			(stroke
				(width 0.1524)
				(type default)
			)
			(layer "F.SilkS")
		)
		(fp_line
			(start -0.7874 0.4064)
			(end -0.7874 -0.4064)
			(stroke
				(width 0.1524)
				(type default)
			)
			(layer "F.SilkS")
		)
		(fp_line
			(start -0.12065 -0.305054)
			(end -0.12065 -0.2794)
			(stroke
				(width 0.1)
				(type default)
			)
			(layer "F.Fab")
		)
		(fp_line
			(start -0.67945 -0.305054)
			(end -0.12065 -0.305054)
			(stroke
				(width 0.1)
				(type default)
			)
			(layer "F.Fab")
		)
		(fp_line
			(start 0.67945 -0.3048)
			(end 0.67945 0.3048)
			(stroke
				(width 0.1)
				(type default)
			)
			(layer "F.Fab")
		)
		(fp_line
			(start 0.12065 -0.3048)
			(end 0.67945 -0.3048)
			(stroke
				(width 0.1)
				(type default)
			)
			(layer "F.Fab")
		)
		(fp_line
			(start 0.12065 -0.2794)
			(end 0.12065 -0.3048)
			(stroke
				(width 0.1)
				(type default)
			)
			(layer "F.Fab")
		)
		(fp_line
			(start -0.12065 -0.2794)
			(end 0.12065 -0.2794)
			(stroke
				(width 0.1)
				(type default)
			)
			(layer "F.Fab")
		)
		(fp_line
			(start 0.120396 0.2794)
			(end -0.12065 0.2794)
			(stroke
				(width 0.1)
				(type default)
			)
			(layer "F.Fab")
		)
		(fp_line
			(start -0.12065 0.2794)
			(end -0.12065 0.3048)
			(stroke
				(width 0.1)
				(type default)
			)
			(layer "F.Fab")
		)
		(fp_line
			(start 0.67945 0.3048)
			(end 0.120396 0.3048)
			(stroke
				(width 0.1)
				(type default)
			)
			(layer "F.Fab")
		)
		(fp_line
			(start 0.120396 0.3048)
			(end 0.120396 0.2794)
			(stroke
				(width 0.1)
				(type default)
			)
			(layer "F.Fab")
		)
		(fp_line
			(start -0.12065 0.3048)
			(end -0.67945 0.3048)
			(stroke
				(width 0.1)
				(type default)
			)
			(layer "F.Fab")
		)
		(fp_line
			(start -0.67945 0.3048)
			(end -0.67945 -0.305054)
			(stroke
				(width 0.1)
				(type default)
			)
			(layer "F.Fab")
		)
		(pad "1" smd circle
			(at -0.40005 0 90)
			(size 0 0)
			(layers "F.Cu" "F.Mask" "F.Paste")
			(net "PVDD11_S3_P0_VCCS")
		)
		(pad "2" smd circle
			(at 0.40005 0 90)
			(size 0 0)
			(layers "F.Cu" "F.Mask" "F.Paste")
			(net "GND")
		)
	)
	(footprint ""
		(layer "F.Cu")
		(at 65.529714 -178.24577 180)
		(property "Reference" "PL8"
			(at 3.654044 5.77723 90)
			(unlocked yes)
			(layer "F.SilkS")
			(effects
				(font
					(size 0.7874 0.5842)
					(thickness 0.1524)
				)
				(justify left)
			)
		)
		(property "Value" ""
			(at 0 0 180)
			(layer "F.Fab")
			(effects
				(font
					(size 1.27 1.27)
				)
			)
		)
		(duplicate_pad_numbers_are_jumpers no)
		(fp_line
			(start 3.750056 5.500116)
			(end 3.750056 -5.500116)
			(stroke
				(width 0.1524)
				(type default)
			)
			(layer "F.SilkS")
		)
		(fp_line
			(start 3.750056 -5.500116)
			(end 2.393442 -5.500116)
			(stroke
				(width 0.1524)
				(type default)
			)
			(layer "F.SilkS")
		)
		(fp_line
			(start 2.393442 5.500116)
			(end 3.750056 5.500116)
			(stroke
				(width 0.1524)
				(type default)
			)
			(layer "F.SilkS")
		)
		(fp_line
			(start -2.393442 5.500116)
			(end -3.750056 5.500116)
			(stroke
				(width 0.1524)
				(type default)
			)
			(layer "F.SilkS")
		)
		(fp_line
			(start -3.750056 5.500116)
			(end -3.750056 -5.500116)
			(stroke
				(width 0.1524)
				(type default)
			)
			(layer "F.SilkS")
		)
		(fp_line
			(start -3.750056 -5.500116)
			(end -2.393442 -5.500116)
			(stroke
				(width 0.1524)
				(type default)
			)
			(layer "F.SilkS")
		)
		(fp_poly
			(pts
				(xy -4.272534 -4.92125) (xy -5.288534 -4.41325) (xy -5.288534 -5.42925)
			)
			(stroke
				(width 0)
				(type default)
			)
			(fill yes)
			(layer "F.SilkS")
		)
		(fp_line
			(start 3.750056 5.500116)
			(end 3.750056 -5.500116)
			(stroke
				(width 0.1)
				(type default)
			)
			(layer "F.Fab")
		)
		(fp_line
			(start 3.750056 -5.500116)
			(end -3.750056 -5.500116)
			(stroke
				(width 0.1)
				(type default)
			)
			(layer "F.Fab")
		)
		(fp_line
			(start -3.750056 5.500116)
			(end 3.750056 5.500116)
			(stroke
				(width 0.1)
				(type default)
			)
			(layer "F.Fab")
		)
		(fp_line
			(start -3.750056 -5.500116)
			(end -3.750056 5.500116)
			(stroke
				(width 0.1)
				(type default)
			)
			(layer "F.Fab")
		)
		(fp_poly
			(pts
				(xy -4.9276 -4.757928) (xy -4.9276 -3.741928) (xy -3.9116 -4.249928)
			)
			(stroke
				(width 0)
				(type default)
			)
			(fill yes)
			(layer "F.Fab")
		)
		(pad "1" smd rect
			(at 0 -4.249928 90)
			(size 2.413 4.5212)
			(layers "F.Cu" "F.Mask" "F.Paste")
			(net "SW_PVDDCR_CPU0_P1_SW6")
		)
		(pad "2" smd rect
			(at 0 -1.175004 90)
			(size 1.3716 4.5212)
			(layers "F.Cu" "F.Mask" "F.Paste")
			(net "IND_CPU0_P1_CPL0")
		)
		(pad "3" smd rect
			(at 0 1.175004 90)
			(size 1.3716 4.5212)
			(layers "F.Cu" "F.Mask" "F.Paste")
			(net "IND_CPU0_P1_CPL6")
		)
		(pad "4" smd rect
			(at 0 4.249928 90)
			(size 2.413 4.5212)
			(layers "F.Cu" "F.Mask" "F.Paste")
			(net "PVDDCR_CPU0_P1")
		)
	)
	(footprint ""
		(layer "F.Cu")
		(at 391.845038 -143.151098 90)
		(property "Reference" "C223"
			(at 0 0 90)
			(layer "F.SilkS")
			(hide yes)
			(effects
				(font
					(size 1.27 1.27)
				)
			)
		)
		(property "Value" ""
			(at 0 0 90)
			(layer "F.Fab")
			(effects
				(font
					(size 1.27 1.27)
				)
			)
		)
		(duplicate_pad_numbers_are_jumpers no)
		(fp_line
			(start 0.7874 -0.4064)
			(end 0.7874 0.4064)
			(stroke
				(width 0.1524)
				(type default)
			)
			(layer "F.SilkS")
		)
		(fp_line
			(start -0.7874 -0.4064)
			(end 0.7874 -0.4064)
			(stroke
				(width 0.1524)
				(type default)
			)
			(layer "F.SilkS")
		)
		(fp_line
			(start 0.7874 0.4064)
			(end -0.7874 0.4064)
			(stroke
				(width 0.1524)
				(type default)
			)
			(layer "F.SilkS")
		)
		(fp_line
			(start -0.7874 0.4064)
			(end -0.7874 -0.4064)
			(stroke
				(width 0.1524)
				(type default)
			)
			(layer "F.SilkS")
		)
		(fp_line
			(start -0.12065 -0.305054)
			(end -0.12065 -0.2794)
			(stroke
				(width 0.1)
				(type default)
			)
			(layer "F.Fab")
		)
		(fp_line
			(start -0.67945 -0.305054)
			(end -0.12065 -0.305054)
			(stroke
				(width 0.1)
				(type default)
			)
			(layer "F.Fab")
		)
		(fp_line
			(start 0.67945 -0.3048)
			(end 0.67945 0.3048)
			(stroke
				(width 0.1)
				(type default)
			)
			(layer "F.Fab")
		)
		(fp_line
			(start 0.12065 -0.3048)
			(end 0.67945 -0.3048)
			(stroke
				(width 0.1)
				(type default)
			)
			(layer "F.Fab")
		)
		(fp_line
			(start 0.12065 -0.2794)
			(end 0.12065 -0.3048)
			(stroke
				(width 0.1)
				(type default)
			)
			(layer "F.Fab")
		)
		(fp_line
			(start -0.12065 -0.2794)
			(end 0.12065 -0.2794)
			(stroke
				(width 0.1)
				(type default)
			)
			(layer "F.Fab")
		)
		(fp_line
			(start 0.120396 0.2794)
			(end -0.12065 0.2794)
			(stroke
				(width 0.1)
				(type default)
			)
			(layer "F.Fab")
		)
		(fp_line
			(start -0.12065 0.2794)
			(end -0.12065 0.3048)
			(stroke
				(width 0.1)
				(type default)
			)
			(layer "F.Fab")
		)
		(fp_line
			(start 0.67945 0.3048)
			(end 0.120396 0.3048)
			(stroke
				(width 0.1)
				(type default)
			)
			(layer "F.Fab")
		)
		(fp_line
			(start 0.120396 0.3048)
			(end 0.120396 0.2794)
			(stroke
				(width 0.1)
				(type default)
			)
			(layer "F.Fab")
		)
		(fp_line
			(start -0.12065 0.3048)
			(end -0.67945 0.3048)
			(stroke
				(width 0.1)
				(type default)
			)
			(layer "F.Fab")
		)
		(fp_line
			(start -0.67945 0.3048)
			(end -0.67945 -0.305054)
			(stroke
				(width 0.1)
				(type default)
			)
			(layer "F.Fab")
		)
		(pad "1" smd circle
			(at -0.40005 0 90)
			(size 0 0)
			(layers "F.Cu" "F.Mask" "F.Paste")
			(net "P1V8_AUX")
		)
		(pad "2" smd circle
			(at 0.40005 0 90)
			(size 0 0)
			(layers "F.Cu" "F.Mask" "F.Paste")
			(net "GND")
		)
	)
	(footprint ""
		(layer "F.Cu")
		(at 192.005712 -355.924358 90)
		(property "Reference" "PR331"
			(at 0 0 90)
			(layer "F.SilkS")
			(hide yes)
			(effects
				(font
					(size 1.27 1.27)
				)
			)
		)
		(property "Value" ""
			(at 0 0 90)
			(layer "F.Fab")
			(effects
				(font
					(size 1.27 1.27)
				)
			)
		)
		(duplicate_pad_numbers_are_jumpers no)
		(fp_line
			(start 0.7874 -0.4064)
			(end 0.7874 0.4064)
			(stroke
				(width 0.1524)
				(type default)
			)
			(layer "F.SilkS")
		)
		(fp_line
			(start -0.7874 -0.4064)
			(end 0.7874 -0.4064)
			(stroke
				(width 0.1524)
				(type default)
			)
			(layer "F.SilkS")
		)
		(fp_line
			(start 0.7874 0.4064)
			(end -0.7874 0.4064)
			(stroke
				(width 0.1524)
				(type default)
			)
			(layer "F.SilkS")
		)
		(fp_line
			(start -0.7874 0.4064)
			(end -0.7874 -0.4064)
			(stroke
				(width 0.1524)
				(type default)
			)
			(layer "F.SilkS")
		)
		(fp_line
			(start -0.12065 -0.305054)
			(end -0.12065 -0.2794)
			(stroke
				(width 0.1)
				(type default)
			)
			(layer "F.Fab")
		)
		(fp_line
			(start -0.67945 -0.305054)
			(end -0.12065 -0.305054)
			(stroke
				(width 0.1)
				(type default)
			)
			(layer "F.Fab")
		)
		(fp_line
			(start 0.67945 -0.3048)
			(end 0.67945 0.3048)
			(stroke
				(width 0.1)
				(type default)
			)
			(layer "F.Fab")
		)
		(fp_line
			(start 0.12065 -0.3048)
			(end 0.67945 -0.3048)
			(stroke
				(width 0.1)
				(type default)
			)
			(layer "F.Fab")
		)
		(fp_line
			(start 0.12065 -0.2794)
			(end 0.12065 -0.3048)
			(stroke
				(width 0.1)
				(type default)
			)
			(layer "F.Fab")
		)
		(fp_line
			(start -0.12065 -0.2794)
			(end 0.12065 -0.2794)
			(stroke
				(width 0.1)
				(type default)
			)
			(layer "F.Fab")
		)
		(fp_line
			(start 0.120396 0.2794)
			(end -0.12065 0.2794)
			(stroke
				(width 0.1)
				(type default)
			)
			(layer "F.Fab")
		)
		(fp_line
			(start -0.12065 0.2794)
			(end -0.12065 0.3048)
			(stroke
				(width 0.1)
				(type default)
			)
			(layer "F.Fab")
		)
		(fp_line
			(start 0.67945 0.3048)
			(end 0.120396 0.3048)
			(stroke
				(width 0.1)
				(type default)
			)
			(layer "F.Fab")
		)
		(fp_line
			(start 0.120396 0.3048)
			(end 0.120396 0.2794)
			(stroke
				(width 0.1)
				(type default)
			)
			(layer "F.Fab")
		)
		(fp_line
			(start -0.12065 0.3048)
			(end -0.67945 0.3048)
			(stroke
				(width 0.1)
				(type default)
			)
			(layer "F.Fab")
		)
		(fp_line
			(start -0.67945 0.3048)
			(end -0.67945 -0.305054)
			(stroke
				(width 0.1)
				(type default)
			)
			(layer "F.Fab")
		)
		(pad "1" smd circle
			(at -0.40005 0 90)
			(size 0 0)
			(layers "F.Cu" "F.Mask" "F.Paste")
			(net "SW_PVDD11_S3_P1_BOOT2")
		)
		(pad "2" smd circle
			(at 0.40005 0 90)
			(size 0 0)
			(layers "F.Cu" "F.Mask" "F.Paste")
			(net "SW_PVDD11_S3_P1_BOOT2_RC")
		)
	)
	(footprint ""
		(layer "F.Cu")
		(at 323.624194 -39.12362 180)
		(property "Reference" "R4567"
			(at 0 0 180)
			(layer "F.SilkS")
			(hide yes)
			(effects
				(font
					(size 1.27 1.27)
				)
			)
		)
		(property "Value" ""
			(at 0 0 180)
			(layer "F.Fab")
			(effects
				(font
					(size 1.27 1.27)
				)
			)
		)
		(duplicate_pad_numbers_are_jumpers no)
		(fp_line
			(start 0.7874 0.4064)
			(end -0.7874 0.4064)
			(stroke
				(width 0.1524)
				(type default)
			)
			(layer "F.SilkS")
		)
		(fp_line
			(start 0.7874 -0.4064)
			(end 0.7874 0.4064)
			(stroke
				(width 0.1524)
				(type default)
			)
			(layer "F.SilkS")
		)
		(fp_line
			(start -0.7874 0.4064)
			(end -0.7874 -0.4064)
			(stroke
				(width 0.1524)
				(type default)
			)
			(layer "F.SilkS")
		)
		(fp_line
			(start -0.7874 -0.4064)
			(end 0.7874 -0.4064)
			(stroke
				(width 0.1524)
				(type default)
			)
			(layer "F.SilkS")
		)
		(fp_line
			(start 0.67945 0.3048)
			(end 0.120396 0.3048)
			(stroke
				(width 0.1)
				(type default)
			)
			(layer "F.Fab")
		)
		(fp_line
			(start 0.67945 -0.3048)
			(end 0.67945 0.3048)
			(stroke
				(width 0.1)
				(type default)
			)
			(layer "F.Fab")
		)
		(fp_line
			(start 0.12065 -0.2794)
			(end 0.12065 -0.3048)
			(stroke
				(width 0.1)
				(type default)
			)
			(layer "F.Fab")
		)
		(fp_line
			(start 0.12065 -0.3048)
			(end 0.67945 -0.3048)
			(stroke
				(width 0.1)
				(type default)
			)
			(layer "F.Fab")
		)
		(fp_line
			(start 0.120396 0.3048)
			(end 0.120396 0.2794)
			(stroke
				(width 0.1)
				(type default)
			)
			(layer "F.Fab")
		)
		(fp_line
			(start 0.120396 0.2794)
			(end -0.12065 0.2794)
			(stroke
				(width 0.1)
				(type default)
			)
			(layer "F.Fab")
		)
		(fp_line
			(start -0.12065 0.3048)
			(end -0.67945 0.3048)
			(stroke
				(width 0.1)
				(type default)
			)
			(layer "F.Fab")
		)
		(fp_line
			(start -0.12065 0.2794)
			(end -0.12065 0.3048)
			(stroke
				(width 0.1)
				(type default)
			)
			(layer "F.Fab")
		)
		(fp_line
			(start -0.12065 -0.2794)
			(end 0.12065 -0.2794)
			(stroke
				(width 0.1)
				(type default)
			)
			(layer "F.Fab")
		)
		(fp_line
			(start -0.12065 -0.305054)
			(end -0.12065 -0.2794)
			(stroke
				(width 0.1)
				(type default)
			)
			(layer "F.Fab")
		)
		(fp_line
			(start -0.67945 0.3048)
			(end -0.67945 -0.305054)
			(stroke
				(width 0.1)
				(type default)
			)
			(layer "F.Fab")
		)
		(fp_line
			(start -0.67945 -0.305054)
			(end -0.12065 -0.305054)
			(stroke
				(width 0.1)
				(type default)
			)
			(layer "F.Fab")
		)
		(pad "1" smd circle
			(at -0.40005 0 180)
			(size 0 0)
			(layers "F.Cu" "F.Mask" "F.Paste")
			(net "P3V3_PDB_AUX_ADC")
		)
		(pad "2" smd circle
			(at 0.40005 0 180)
			(size 0 0)
			(layers "F.Cu" "F.Mask" "F.Paste")
			(net "P1V581_PDB_ADC")
		)
	)
	(footprint ""
		(layer "F.Cu")
		(at 244.115336 -393.909296 -90)
		(property "Reference" "PR6001"
			(at -4.524248 3.668268 90)
			(unlocked yes)
			(layer "F.SilkS")
			(effects
				(font
					(size 0.7874 0.5842)
					(thickness 0.1524)
				)
				(justify left)
			)
		)
		(property "Value" ""
			(at 0 0 270)
			(layer "F.Fab")
			(effects
				(font
					(size 1.27 1.27)
				)
			)
		)
		(duplicate_pad_numbers_are_jumpers no)
		(fp_line
			(start -3.9878 3.5814)
			(end -3.9878 -3.5814)
			(stroke
				(width 0.1524)
				(type default)
			)
			(layer "F.SilkS")
		)
		(fp_line
			(start 3.9878 3.5814)
			(end -3.9878 3.5814)
			(stroke
				(width 0.1524)
				(type default)
			)
			(layer "F.SilkS")
		)
		(fp_line
			(start -3.9878 -3.5814)
			(end 3.9878 -3.5814)
			(stroke
				(width 0.1524)
				(type default)
			)
			(layer "F.SilkS")
		)
		(fp_line
			(start 3.9878 -3.5814)
			(end 3.9878 3.5814)
			(stroke
				(width 0.1524)
				(type default)
			)
			(layer "F.SilkS")
		)
		(fp_line
			(start -3.5306 3.353054)
			(end -3.5306 -3.353054)
			(stroke
				(width 0.1)
				(type default)
			)
			(layer "F.Fab")
		)
		(fp_line
			(start 3.5306 3.353054)
			(end -3.5306 3.353054)
			(stroke
				(width 0.1)
				(type default)
			)
			(layer "F.Fab")
		)
		(fp_line
			(start -3.5306 -3.353054)
			(end 3.5306 -3.353054)
			(stroke
				(width 0.1)
				(type default)
			)
			(layer "F.Fab")
		)
		(fp_line
			(start 3.5306 -3.353054)
			(end 3.5306 3.353054)
			(stroke
				(width 0.1)
				(type default)
			)
			(layer "F.Fab")
		)
		(pad "1A" smd rect
			(at -2.249932 0 90)
			(size 3.2004 6.858)
			(layers "F.Cu" "F.Mask" "F.Paste")
			(net "P12V_PSU")
		)
		(pad "1B" smd rect
			(at -0.776732 0 270)
			(size 0.254 0.508)
			(layers "F.Cu" "F.Mask" "F.Paste")
			(net "P12V_HSC_SENSE2_R1_P")
		)
		(pad "2A" smd rect
			(at 2.249932 0 90)
			(size 3.2004 6.858)
			(layers "F.Cu" "F.Mask" "F.Paste")
			(net "P12V_MAIN_R")
		)
		(pad "2B" smd rect
			(at 0.776732 0 270)
			(size 0.254 0.508)
			(layers "F.Cu" "F.Mask" "F.Paste")
			(net "P12V_HSC_SENSE2_R1_N")
		)
	)
)
